# BASEBOARD_FAB2 (Tioga Pass) — schematic netlist excerpt (pin names and nets, part order shuffled) for the footprints in the layout excerpt that follows; sources: Cadence DE-HDL packaged netlist, KiCad conversion of Wiwynn_Tioga_Pass_MB.brd

C5D41  CAP_A  22.0UF 4V 20% X6S  pkg 0603V  page 42 : A = PVCCIN_CPU0 ; B = GND
R4E15  RES  1.00K 1% EMPTY  pkg 0402  page 204 : A = VSENSE_PVCCIN_CPU0_P ; B = VSENSE_PVCCIN_CPU0_N
C10W3  CAP_A  0.01UF 25V 10% X7R  pkg 0402V  page 251 : A = PUMP_TACH0 ; B = GND

(kicad_pcb
	(version 20260206)
	(generator "pcbnew")
	(generator_version "10.0")
	(general
		(thickness 1.6)
		(legacy_teardrops no)
	)
	(paper "A4")
	(title_block
		(title "Wiwynn_Tioga_Pass_MB.brd")
		(comment 1 "Tioga Pass / footprints 1914-1916 of 4770")
	)
	(layers
		(0 "F.Cu" signal "TOP")
		(4 "In1.Cu" signal "L2GND")
		(6 "In2.Cu" signal "L3")
		(8 "In3.Cu" signal "L4GND")
		(10 "In4.Cu" signal "L5")
		(12 "In5.Cu" signal "L6GND")
		(14 "In6.Cu" signal "L7VCC")
		(16 "In7.Cu" signal "L8VCC")
		(18 "In8.Cu" signal "L9GND")
		(20 "In9.Cu" signal "L10")
		(22 "In10.Cu" signal "L11GND")
		(24 "In11.Cu" signal "L12")
		(26 "In12.Cu" signal "L13GND")
		(2 "B.Cu" signal "BOTTOM")
		(9 "F.Adhes" user "F.Adhesive")
		(11 "B.Adhes" user "B.Adhesive")
		(13 "F.Paste" user "Package Geometry/Pastemask Top")
		(15 "B.Paste" user "Package Geometry/Pastemask Bottom")
		(5 "F.SilkS" user "Ref Des/Silkscreen Top")
		(7 "B.SilkS" user "Ref Des/Silkscreen Bottom")
		(1 "F.Mask" user "Board Geometry/Soldermask Top")
		(3 "B.Mask" user "Board Geometry/Soldermask Bottom")
		(17 "Dwgs.User" user "User.Drawings")
		(19 "Cmts.User" user "User.Comments")
		(21 "Eco1.User" user "User.Eco1")
		(23 "Eco2.User" user "User.Eco2")
		(25 "Edge.Cuts" user "Board Geometry/Outline")
		(27 "Margin" user)
		(31 "F.CrtYd" user "Package Geometry/Place Bound Top")
		(29 "B.CrtYd" user "Package Geometry/Place Bound Bottom")
		(35 "F.Fab" user "Ref Des/Assembly Top")
		(33 "B.Fab" user "Ref Des/Assembly Bottom")
	)
	(footprint ""
		(layer "F.Cu")
		(at 260.697472 -73.318116)
		(property "Reference" "C5D41"
			(at 0 0 0)
			(layer "F.SilkS")
			(hide yes)
			(effects
				(font
					(size 1.27 1.27)
				)
			)
		)
		(property "Value" ""
			(at 0 0 0)
			(layer "F.Fab")
			(effects
				(font
					(size 1.27 1.27)
				)
			)
		)
		(duplicate_pad_numbers_are_jumpers no)
		(fp_poly
			(pts
				(xy -0.4953 -0.2032) (xy 0.4953 -0.2032) (xy 0.4953 1.6002) (xy -0.4953 1.6002)
			)
			(stroke
				(width 0)
				(type default)
			)
			(fill no)
			(layer "F.CrtYd")
		)
		(fp_line
			(start -0.4953 -0.2032)
			(end 0.4953 -0.2032)
			(stroke
				(width 0.1)
				(type default)
			)
			(layer "F.Fab")
		)
		(fp_line
			(start -0.4953 1.6002)
			(end -0.4953 -0.2032)
			(stroke
				(width 0.1)
				(type default)
			)
			(layer "F.Fab")
		)
		(fp_line
			(start 0.4953 -0.2032)
			(end 0.4953 1.6002)
			(stroke
				(width 0.1)
				(type default)
			)
			(layer "F.Fab")
		)
		(fp_line
			(start 0.4953 1.6002)
			(end -0.4953 1.6002)
			(stroke
				(width 0.1)
				(type default)
			)
			(layer "F.Fab")
		)
		(pad "1" smd rect
			(at 0 0)
			(size 0.762 0.889)
			(layers "F.Cu" "F.Mask" "F.Paste")
			(net "PVCCIN_CPU0")
		)
		(pad "2" smd rect
			(at 0 1.397)
			(size 0.762 0.889)
			(layers "F.Cu" "F.Mask" "F.Paste")
			(net "GND")
		)
		(zone
			(layer "F.Cu")
			(hatch none 0.5)
			(connect_pads
				(clearance 0)
			)
			(min_thickness 0.25)
			(keepout
				(tracks not_allowed)
				(vias allowed)
				(pads allowed)
				(copperpour not_allowed)
				(footprints allowed)
			)
			(placement
				(enabled no)
				(sheetname "")
			)
			(fill
				(thermal_gap 0.5)
				(thermal_bridge_width 0.5)
				(island_removal_mode 0)
			)
			(polygon
				(pts
					(xy 260.316472 -72.873616) (xy 261.078472 -72.873616) (xy 261.078472 -72.365616) (xy 260.316472 -72.365616)
				)
			)
		)
	)
	(footprint ""
		(layer "F.Cu")
		(at 204.2668 -50.5714)
		(property "Reference" "R4E15"
			(at 0 0 0)
			(layer "F.SilkS")
			(hide yes)
			(effects
				(font
					(size 1.27 1.27)
				)
			)
		)
		(property "Value" ""
			(at 0 0 0)
			(layer "F.Fab")
			(effects
				(font
					(size 1.27 1.27)
				)
			)
		)
		(duplicate_pad_numbers_are_jumpers no)
		(fp_poly
			(pts
				(xy -0.2794 -0.1016) (xy 0.2794 -0.1016) (xy 0.2794 0.9906) (xy -0.2794 0.9906)
			)
			(stroke
				(width 0)
				(type default)
			)
			(fill no)
			(layer "F.CrtYd")
		)
		(fp_line
			(start -0.2794 -0.1016)
			(end -0.2794 0.9906)
			(stroke
				(width 0.1)
				(type default)
			)
			(layer "F.Fab")
		)
		(fp_line
			(start -0.2794 0.9906)
			(end 0.2794 0.9906)
			(stroke
				(width 0.1)
				(type default)
			)
			(layer "F.Fab")
		)
		(fp_line
			(start 0.2794 -0.1016)
			(end -0.2794 -0.1016)
			(stroke
				(width 0.1)
				(type default)
			)
			(layer "F.Fab")
		)
		(fp_line
			(start 0.2794 0.9906)
			(end 0.2794 -0.1016)
			(stroke
				(width 0.1)
				(type default)
			)
			(layer "F.Fab")
		)
		(pad "1" smd rect
			(at 0 0)
			(size 0.508 0.508)
			(layers "F.Cu" "F.Mask" "F.Paste")
			(net "VSENSE_PVCCIN_CPU0_P")
		)
		(pad "2" smd rect
			(at 0 0.889)
			(size 0.508 0.508)
			(layers "F.Cu" "F.Mask" "F.Paste")
			(net "VSENSE_PVCCIN_CPU0_N")
		)
		(zone
			(layer "F.Cu")
			(hatch none 0.5)
			(connect_pads
				(clearance 0)
			)
			(min_thickness 0.25)
			(keepout
				(tracks allowed)
				(vias not_allowed)
				(pads allowed)
				(copperpour not_allowed)
				(footprints allowed)
			)
			(placement
				(enabled no)
				(sheetname "")
			)
			(fill
				(thermal_gap 0.5)
				(thermal_bridge_width 0.5)
				(island_removal_mode 0)
			)
			(polygon
				(pts
					(xy 204.0128 -50.3174) (xy 204.5208 -50.3174) (xy 204.5208 -49.9364) (xy 204.0128 -49.9364)
				)
			)
		)
		(zone
			(layer "F.Cu")
			(hatch none 0.5)
			(connect_pads
				(clearance 0)
			)
			(min_thickness 0.25)
			(keepout
				(tracks not_allowed)
				(vias allowed)
				(pads allowed)
				(copperpour not_allowed)
				(footprints allowed)
			)
			(placement
				(enabled no)
				(sheetname "")
			)
			(fill
				(thermal_gap 0.5)
				(thermal_bridge_width 0.5)
				(island_removal_mode 0)
			)
			(polygon
				(pts
					(xy 204.0128 -49.9364) (xy 204.5208 -49.9364) (xy 204.5208 -50.3174) (xy 204.0128 -50.3174)
				)
			)
		)
	)
	(footprint ""
		(layer "F.Cu")
		(at 436.499 -19.3675)
		(property "Reference" "C10W3"
			(at -0.8382 -0.67818 0)
			(unlocked yes)
			(layer "F.SilkS")
			(effects
				(font
					(size 0.4064 0.254)
					(thickness 0.1524)
				)
				(justify left)
			)
		)
		(property "Value" ""
			(at 0 0 0)
			(layer "F.Fab")
			(effects
				(font
					(size 1.27 1.27)
				)
			)
		)
		(duplicate_pad_numbers_are_jumpers no)
		(fp_poly
			(pts
				(xy 0.3048 -0.1016) (xy 0.3048 0.9906) (xy -0.3048 0.9906) (xy -0.3048 -0.1016)
			)
			(stroke
				(width 0)
				(type default)
			)
			(fill no)
			(layer "F.CrtYd")
		)
		(fp_line
			(start -0.3048 -0.1016)
			(end -0.3048 0.9906)
			(stroke
				(width 0.1)
				(type default)
			)
			(layer "F.Fab")
		)
		(fp_line
			(start -0.3048 0.9906)
			(end 0.3048 0.9906)
			(stroke
				(width 0.1)
				(type default)
			)
			(layer "F.Fab")
		)
		(fp_line
			(start 0.3048 -0.1016)
			(end -0.3048 -0.1016)
			(stroke
				(width 0.1)
				(type default)
			)
			(layer "F.Fab")
		)
		(fp_line
			(start 0.3048 0.9906)
			(end 0.3048 -0.1016)
			(stroke
				(width 0.1)
				(type default)
			)
			(layer "F.Fab")
		)
		(pad "1" smd rect
			(at 0 0)
			(size 0.508 0.508)
			(layers "F.Cu" "F.Mask" "F.Paste")
			(net "PUMP_TACH0")
		)
		(pad "2" smd rect
			(at 0 0.889)
			(size 0.508 0.508)
			(layers "F.Cu" "F.Mask" "F.Paste")
			(net "GND")
		)
		(zone
			(layer "F.Cu")
			(hatch none 0.5)
			(connect_pads
				(clearance 0)
			)
			(min_thickness 0.25)
			(keepout
				(tracks allowed)
				(vias not_allowed)
				(pads allowed)
				(copperpour not_allowed)
				(footprints allowed)
			)
			(placement
				(enabled no)
				(sheetname "")
			)
			(fill
				(thermal_gap 0.5)
				(thermal_bridge_width 0.5)
				(island_removal_mode 0)
			)
			(polygon
				(pts
					(xy 436.245 -19.1135) (xy 436.753 -19.1135) (xy 436.753 -18.7325) (xy 436.245 -18.7325)
				)
			)
		)
		(zone
			(layer "F.Cu")
			(hatch none 0.5)
			(connect_pads
				(clearance 0)
			)
			(min_thickness 0.25)
			(keepout
				(tracks not_allowed)
				(vias allowed)
				(pads allowed)
				(copperpour not_allowed)
				(footprints allowed)
			)
			(placement
				(enabled no)
				(sheetname "")
			)
			(fill
				(thermal_gap 0.5)
				(thermal_bridge_width 0.5)
				(island_removal_mode 0)
			)
			(polygon
				(pts
					(xy 436.245 -18.7325) (xy 436.753 -18.7325) (xy 436.753 -19.1135) (xy 436.245 -19.1135)
				)
			)
		)
	)
)
